(kicad_pcb
	(version 20260206)
	(generator "pcbnew")
	(generator_version "10.0")
	(general
		(thickness 1.6)
		(legacy_teardrops no)
	)
	(paper "A4")
	(title_block
		(title "v1-chassis-manager — T6M_CM_d_v01_1031_1645.brd")
		(comment 1 "Open CloudServer (Microsoft) / footprints 1816-1825 of 2512")
	)
	(layers
		(0 "F.Cu" signal "TOP")
		(4 "In1.Cu" signal "GND1")
		(6 "In2.Cu" signal "IN1")
		(8 "In3.Cu" signal "VCC1")
		(10 "In4.Cu" signal "VCC2")
		(12 "In5.Cu" signal "GND2")
		(14 "In6.Cu" signal "IN2")
		(16 "In7.Cu" signal "IN3")
		(18 "In8.Cu" signal "GND3")
		(2 "B.Cu" signal "BOTTOM")
		(9 "F.Adhes" user "F.Adhesive")
		(11 "B.Adhes" user "B.Adhesive")
		(13 "F.Paste" user "Package Geometry/Pastemask Top")
		(15 "B.Paste" user "Package Geometry/Pastemask Bottom")
		(5 "F.SilkS" user "Ref Des/Silkscreen Top")
		(7 "B.SilkS" user "Ref Des/Silkscreen Bottom")
		(1 "F.Mask" user "Board Geometry/Soldermask Top")
		(3 "B.Mask" user "Board Geometry/Soldermask Bottom")
		(17 "Dwgs.User" user "User.Drawings")
		(19 "Cmts.User" user "User.Comments")
		(21 "Eco1.User" user "User.Eco1")
		(23 "Eco2.User" user "User.Eco2")
		(25 "Edge.Cuts" user "Board Geometry/Outline")
		(27 "Margin" user)
		(31 "F.CrtYd" user "Package Geometry/Place Bound Top")
		(29 "B.CrtYd" user "Package Geometry/Place Bound Bottom")
		(35 "F.Fab" user "Ref Des/Assembly Top")
		(33 "B.Fab" user "Ref Des/Assembly Bottom")
	)
	(footprint ""
		(layer "B.Cu")
		(at 78.83144 -167.425624 180)
		(property "Reference" "R790"
			(at -30.603698 -20.726146 0)
			(unlocked yes)
			(layer "B.SilkS")
			(effects
				(font
					(size 0.7874 0.5842)
					(thickness 0.1524)
				)
				(justify left mirror)
			)
		)
		(property "Value" ""
			(at 0 0 0)
			(layer "B.Fab")
			(effects
				(font
					(size 1.27 1.27)
				)
				(justify mirror)
			)
		)
		(duplicate_pad_numbers_are_jumpers no)
		(fp_line
			(start 0.7874 0.4064)
			(end 0.7874 -0.4064)
			(stroke
				(width 0.1524)
				(type default)
			)
			(layer "B.SilkS")
		)
		(fp_line
			(start 0.7874 -0.4064)
			(end -0.7874 -0.4064)
			(stroke
				(width 0.1524)
				(type default)
			)
			(layer "B.SilkS")
		)
		(fp_line
			(start -0.7874 0.4064)
			(end 0.7874 0.4064)
			(stroke
				(width 0.1524)
				(type default)
			)
			(layer "B.SilkS")
		)
		(fp_line
			(start -0.7874 -0.4064)
			(end -0.7874 0.4064)
			(stroke
				(width 0.1524)
				(type default)
			)
			(layer "B.SilkS")
		)
		(fp_poly
			(pts
				(xy 0.508 0.2794) (xy 0.508 0.2286) (xy 0.635 0.2286) (xy 0.635 -0.254) (xy 0.5334 -0.254) (xy 0.5334 -0.2794)
				(xy -0.5334 -0.2794) (xy -0.5334 -0.254) (xy -0.635 -0.254) (xy -0.635 0.254) (xy -0.5334 0.254)
				(xy -0.5334 0.2794)
			)
			(stroke
				(width 0)
				(type default)
			)
			(fill no)
			(layer "B.CrtYd")
		)
		(pad "1" smd rect
			(at -0.40005 0)
			(size 0.4572 0.508)
			(layers "B.Cu" "B.Mask" "B.Paste")
			(net "UART_SW_S4_N")
		)
		(pad "2" smd rect
			(at 0.40005 0)
			(size 0.4572 0.508)
			(layers "B.Cu" "B.Mask" "B.Paste")
			(net "P3V3_NODE1")
		)
	)
	(footprint ""
		(layer "B.Cu")
		(at 94.211394 -187.822586)
		(property "Reference" "C668"
			(at 1.315466 -5.985002 0)
			(unlocked yes)
			(layer "B.SilkS")
			(effects
				(font
					(size 0.7874 0.5842)
					(thickness 0.1524)
				)
				(justify left mirror)
			)
		)
		(property "Value" ""
			(at 0 0 0)
			(layer "B.Fab")
			(effects
				(font
					(size 1.27 1.27)
				)
				(justify mirror)
			)
		)
		(duplicate_pad_numbers_are_jumpers no)
		(fp_line
			(start -0.7874 -0.4064)
			(end -0.7874 0.4064)
			(stroke
				(width 0.1524)
				(type default)
			)
			(layer "B.SilkS")
		)
		(fp_line
			(start -0.7874 0.4064)
			(end 0.7874 0.4064)
			(stroke
				(width 0.1524)
				(type default)
			)
			(layer "B.SilkS")
		)
		(fp_line
			(start 0 0.381)
			(end 0 -0.381)
			(stroke
				(width 0.1524)
				(type default)
			)
			(layer "B.SilkS")
		)
		(fp_line
			(start 0.7874 -0.4064)
			(end -0.7874 -0.4064)
			(stroke
				(width 0.1524)
				(type default)
			)
			(layer "B.SilkS")
		)
		(fp_line
			(start 0.7874 0.4064)
			(end 0.7874 -0.4064)
			(stroke
				(width 0.1524)
				(type default)
			)
			(layer "B.SilkS")
		)
		(fp_poly
			(pts
				(xy 0.5334 0.254) (xy 0.635 0.254) (xy 0.635 0.2286) (xy 0.635 -0.254) (xy 0.5334 -0.254) (xy 0.5334 -0.2794)
				(xy -0.5334 -0.2794) (xy -0.5334 -0.254) (xy -0.635 -0.254) (xy -0.635 0.254) (xy -0.5334 0.254)
				(xy -0.5334 0.2794) (xy 0.508 0.2794) (xy 0.5334 0.2794)
			)
			(stroke
				(width 0)
				(type default)
			)
			(fill no)
			(layer "B.CrtYd")
		)
		(pad "1" smd rect
			(at -0.40005 0 180)
			(size 0.4572 0.508)
			(layers "B.Cu" "B.Mask" "B.Paste")
			(net "T5_NODE4_EN_R")
		)
		(pad "2" smd rect
			(at 0.40005 0 180)
			(size 0.4572 0.508)
			(layers "B.Cu" "B.Mask" "B.Paste")
			(net "GND")
		)
	)
	(footprint ""
		(layer "B.Cu")
		(at 57.430416 -130.01371 180)
		(property "Reference" "C288"
			(at 40.223948 -53.201316 0)
			(unlocked yes)
			(layer "B.SilkS")
			(effects
				(font
					(size 0.7874 0.5842)
					(thickness 0.1524)
				)
				(justify left mirror)
			)
		)
		(property "Value" ""
			(at 0 0 0)
			(layer "B.Fab")
			(effects
				(font
					(size 1.27 1.27)
				)
				(justify mirror)
			)
		)
		(duplicate_pad_numbers_are_jumpers no)
		(fp_line
			(start 0.7874 0.4064)
			(end 0.7874 -0.4064)
			(stroke
				(width 0.1524)
				(type default)
			)
			(layer "B.SilkS")
		)
		(fp_line
			(start 0.7874 -0.4064)
			(end -0.7874 -0.4064)
			(stroke
				(width 0.1524)
				(type default)
			)
			(layer "B.SilkS")
		)
		(fp_line
			(start 0 0.381)
			(end 0 -0.381)
			(stroke
				(width 0.1524)
				(type default)
			)
			(layer "B.SilkS")
		)
		(fp_line
			(start -0.7874 0.4064)
			(end 0.7874 0.4064)
			(stroke
				(width 0.1524)
				(type default)
			)
			(layer "B.SilkS")
		)
		(fp_line
			(start -0.7874 -0.4064)
			(end -0.7874 0.4064)
			(stroke
				(width 0.1524)
				(type default)
			)
			(layer "B.SilkS")
		)
		(fp_poly
			(pts
				(xy 0.5334 0.254) (xy 0.635 0.254) (xy 0.635 0.2286) (xy 0.635 -0.254) (xy 0.5334 -0.254) (xy 0.5334 -0.2794)
				(xy -0.5334 -0.2794) (xy -0.5334 -0.254) (xy -0.635 -0.254) (xy -0.635 0.254) (xy -0.5334 0.254)
				(xy -0.5334 0.2794) (xy 0.508 0.2794) (xy 0.5334 0.2794)
			)
			(stroke
				(width 0)
				(type default)
			)
			(fill no)
			(layer "B.CrtYd")
		)
		(pad "1" smd rect
			(at -0.40005 0)
			(size 0.4572 0.508)
			(layers "B.Cu" "B.Mask" "B.Paste")
			(net "P1V26_BMC_NODE1")
		)
		(pad "2" smd rect
			(at 0.40005 0)
			(size 0.4572 0.508)
			(layers "B.Cu" "B.Mask" "B.Paste")
			(net "GND")
		)
	)
	(footprint ""
		(layer "B.Cu")
		(at 142.07236 -175.045624 180)
		(property "Reference" "R732"
			(at 1.287272 0.298196 0)
			(unlocked yes)
			(layer "B.SilkS")
			(effects
				(font
					(size 0.7874 0.5842)
					(thickness 0.1524)
				)
				(justify left mirror)
			)
		)
		(property "Value" ""
			(at 0 0 0)
			(layer "B.Fab")
			(effects
				(font
					(size 1.27 1.27)
				)
				(justify mirror)
			)
		)
		(duplicate_pad_numbers_are_jumpers no)
		(fp_line
			(start 0.7874 0.4064)
			(end 0.7874 -0.4064)
			(stroke
				(width 0.1524)
				(type default)
			)
			(layer "B.SilkS")
		)
		(fp_line
			(start 0.7874 -0.4064)
			(end -0.7874 -0.4064)
			(stroke
				(width 0.1524)
				(type default)
			)
			(layer "B.SilkS")
		)
		(fp_line
			(start -0.7874 0.4064)
			(end 0.7874 0.4064)
			(stroke
				(width 0.1524)
				(type default)
			)
			(layer "B.SilkS")
		)
		(fp_line
			(start -0.7874 -0.4064)
			(end -0.7874 0.4064)
			(stroke
				(width 0.1524)
				(type default)
			)
			(layer "B.SilkS")
		)
		(fp_poly
			(pts
				(xy 0.508 0.2794) (xy 0.508 0.2286) (xy 0.635 0.2286) (xy 0.635 -0.254) (xy 0.5334 -0.254) (xy 0.5334 -0.2794)
				(xy -0.5334 -0.2794) (xy -0.5334 -0.254) (xy -0.635 -0.254) (xy -0.635 0.254) (xy -0.5334 0.254)
				(xy -0.5334 0.2794)
			)
			(stroke
				(width 0)
				(type default)
			)
			(fill no)
			(layer "B.CrtYd")
		)
		(pad "1" smd rect
			(at -0.40005 0)
			(size 0.4572 0.508)
			(layers "B.Cu" "B.Mask" "B.Paste")
			(net "T10_NODE1_EN")
		)
		(pad "2" smd rect
			(at 0.40005 0)
			(size 0.4572 0.508)
			(layers "B.Cu" "B.Mask" "B.Paste")
			(net "P5V_NODE1")
		)
	)
	(footprint ""
		(layer "B.Cu")
		(at 69.471286 -118.758462 -90)
		(property "Reference" "R339"
			(at 5.09016 0.669544 270)
			(unlocked yes)
			(layer "B.SilkS")
			(effects
				(font
					(size 0.7874 0.5842)
					(thickness 0.1524)
				)
				(justify left mirror)
			)
		)
		(property "Value" ""
			(at 0 0 90)
			(layer "B.Fab")
			(effects
				(font
					(size 1.27 1.27)
				)
				(justify mirror)
			)
		)
		(duplicate_pad_numbers_are_jumpers no)
		(fp_line
			(start -0.7874 0.4064)
			(end 0.7874 0.4064)
			(stroke
				(width 0.1524)
				(type default)
			)
			(layer "B.SilkS")
		)
		(fp_line
			(start 0.7874 0.4064)
			(end 0.7874 -0.4064)
			(stroke
				(width 0.1524)
				(type default)
			)
			(layer "B.SilkS")
		)
		(fp_line
			(start -0.7874 -0.4064)
			(end -0.7874 0.4064)
			(stroke
				(width 0.1524)
				(type default)
			)
			(layer "B.SilkS")
		)
		(fp_line
			(start 0.7874 -0.4064)
			(end -0.7874 -0.4064)
			(stroke
				(width 0.1524)
				(type default)
			)
			(layer "B.SilkS")
		)
		(fp_poly
			(pts
				(xy 0.508 0.2794) (xy 0.508 0.2286) (xy 0.635 0.2286) (xy 0.635 -0.254) (xy 0.5334 -0.254) (xy 0.5334 -0.2794)
				(xy -0.5334 -0.2794) (xy -0.5334 -0.254) (xy -0.635 -0.254) (xy -0.635 0.254) (xy -0.5334 0.254)
				(xy -0.5334 0.2794)
			)
			(stroke
				(width 0)
				(type default)
			)
			(fill no)
			(layer "B.CrtYd")
		)
		(pad "1" smd rect
			(at -0.40005 0 90)
			(size 0.4572 0.508)
			(layers "B.Cu" "B.Mask" "B.Paste")
			(net "P3V3_NODE1")
		)
		(pad "2" smd rect
			(at 0.40005 0 90)
			(size 0.4572 0.508)
			(layers "B.Cu" "B.Mask" "B.Paste")
			(net "BMC_ROMA23")
		)
	)
	(footprint ""
		(layer "B.Cu")
		(at 116.068602 -123.297442 -90)
		(property "Reference" "PC92"
			(at -3.090164 -0.20701 270)
			(unlocked yes)
			(layer "B.SilkS")
			(effects
				(font
					(size 0.7874 0.5842)
					(thickness 0.1524)
				)
				(justify left mirror)
			)
		)
		(property "Value" ""
			(at 0 0 90)
			(layer "B.Fab")
			(effects
				(font
					(size 1.27 1.27)
				)
				(justify mirror)
			)
		)
		(duplicate_pad_numbers_are_jumpers no)
		(fp_line
			(start -2.2098 0.9398)
			(end 2.2098 0.9398)
			(stroke
				(width 0.1524)
				(type default)
			)
			(layer "B.SilkS")
		)
		(fp_line
			(start 2.2098 0.9398)
			(end 2.2098 -0.9398)
			(stroke
				(width 0.1524)
				(type default)
			)
			(layer "B.SilkS")
		)
		(fp_line
			(start -2.2098 -0.9398)
			(end -2.2098 0.9398)
			(stroke
				(width 0.1524)
				(type default)
			)
			(layer "B.SilkS")
		)
		(fp_line
			(start 0 -0.9398)
			(end 0 0.9398)
			(stroke
				(width 0.1524)
				(type default)
			)
			(layer "B.SilkS")
		)
		(fp_line
			(start 2.2098 -0.9398)
			(end -2.2098 -0.9398)
			(stroke
				(width 0.1524)
				(type default)
			)
			(layer "B.SilkS")
		)
		(fp_poly
			(pts
				(xy 1.6764 0.889) (xy 1.6764 0.7874) (xy 2.0574 0.7874) (xy 2.0574 -0.7874) (xy 1.6764 -0.7874)
				(xy 1.6764 -0.9398) (xy -1.6764 -0.9398) (xy -1.6764 -0.7874) (xy -2.0574 -0.7874) (xy -2.0574 0.7874)
				(xy -1.6764 0.7874) (xy -1.6764 0.9398) (xy 1.6764 0.9398)
			)
			(stroke
				(width 0)
				(type default)
			)
			(fill no)
			(layer "B.CrtYd")
		)
		(fp_line
			(start -1.700022 0.899922)
			(end 1.700022 0.899922)
			(stroke
				(width 0.1)
				(type default)
			)
			(layer "B.Fab")
		)
		(fp_line
			(start 1.700022 0.899922)
			(end 1.700022 -0.899922)
			(stroke
				(width 0.1)
				(type default)
			)
			(layer "B.Fab")
		)
		(fp_line
			(start -1.700022 -0.899922)
			(end -1.700022 0.899922)
			(stroke
				(width 0.1)
				(type default)
			)
			(layer "B.Fab")
		)
		(fp_line
			(start 1.700022 -0.899922)
			(end -1.700022 -0.899922)
			(stroke
				(width 0.1)
				(type default)
			)
			(layer "B.Fab")
		)
		(pad "1" smd rect
			(at -1.4732 0 90)
			(size 1.1684 1.5748)
			(layers "B.Cu" "B.Mask" "B.Paste")
			(net "SW_VR_PVCCP_NODE1_VIN_FLT")
		)
		(pad "2" smd rect
			(at 1.4732 0 90)
			(size 1.1684 1.5748)
			(layers "B.Cu" "B.Mask" "B.Paste")
			(net "GND")
		)
	)
	(footprint ""
		(layer "B.Cu")
		(at 129.468372 -171.36364)
		(property "Reference" "R982"
			(at 5.856224 -0.371348 0)
			(unlocked yes)
			(layer "B.SilkS")
			(effects
				(font
					(size 0.7874 0.5842)
					(thickness 0.1524)
				)
				(justify left mirror)
			)
		)
		(property "Value" ""
			(at 0 0 0)
			(layer "B.Fab")
			(effects
				(font
					(size 1.27 1.27)
				)
				(justify mirror)
			)
		)
		(duplicate_pad_numbers_are_jumpers no)
		(fp_line
			(start -0.7874 -0.4064)
			(end -0.7874 0.4064)
			(stroke
				(width 0.1524)
				(type default)
			)
			(layer "B.SilkS")
		)
		(fp_line
			(start -0.7874 0.4064)
			(end 0.7874 0.4064)
			(stroke
				(width 0.1524)
				(type default)
			)
			(layer "B.SilkS")
		)
		(fp_line
			(start 0.7874 -0.4064)
			(end -0.7874 -0.4064)
			(stroke
				(width 0.1524)
				(type default)
			)
			(layer "B.SilkS")
		)
		(fp_line
			(start 0.7874 0.4064)
			(end 0.7874 -0.4064)
			(stroke
				(width 0.1524)
				(type default)
			)
			(layer "B.SilkS")
		)
		(fp_poly
			(pts
				(xy 0.508 0.2794) (xy 0.508 0.2286) (xy 0.635 0.2286) (xy 0.635 -0.254) (xy 0.5334 -0.254) (xy 0.5334 -0.2794)
				(xy -0.5334 -0.2794) (xy -0.5334 -0.254) (xy -0.635 -0.254) (xy -0.635 0.254) (xy -0.5334 0.254)
				(xy -0.5334 0.2794)
			)
			(stroke
				(width 0)
				(type default)
			)
			(fill no)
			(layer "B.CrtYd")
		)
		(pad "1" smd rect
			(at -0.40005 0 180)
			(size 0.4572 0.508)
			(layers "B.Cu" "B.Mask" "B.Paste")
			(net "UART_T8_NODE1_TXD")
		)
		(pad "2" smd rect
			(at 0.40005 0 180)
			(size 0.4572 0.508)
			(layers "B.Cu" "B.Mask" "B.Paste")
			(net "UART_T8_NODE1_TXD_R")
		)
	)
	(footprint ""
		(layer "B.Cu")
		(at 119.49176 -188.126624 -90)
		(property "Reference" "C638"
			(at -4.080256 -0.623316 270)
			(unlocked yes)
			(layer "B.SilkS")
			(effects
				(font
					(size 0.7874 0.5842)
					(thickness 0.1524)
				)
				(justify left mirror)
			)
		)
		(property "Value" ""
			(at 0 0 90)
			(layer "B.Fab")
			(effects
				(font
					(size 1.27 1.27)
				)
				(justify mirror)
			)
		)
		(duplicate_pad_numbers_are_jumpers no)
		(fp_line
			(start -0.7874 0.4064)
			(end 0.7874 0.4064)
			(stroke
				(width 0.1524)
				(type default)
			)
			(layer "B.SilkS")
		)
		(fp_line
			(start 0.7874 0.4064)
			(end 0.7874 -0.4064)
			(stroke
				(width 0.1524)
				(type default)
			)
			(layer "B.SilkS")
		)
		(fp_line
			(start 0 0.381)
			(end 0 -0.381)
			(stroke
				(width 0.1524)
				(type default)
			)
			(layer "B.SilkS")
		)
		(fp_line
			(start -0.7874 -0.4064)
			(end -0.7874 0.4064)
			(stroke
				(width 0.1524)
				(type default)
			)
			(layer "B.SilkS")
		)
		(fp_line
			(start 0.7874 -0.4064)
			(end -0.7874 -0.4064)
			(stroke
				(width 0.1524)
				(type default)
			)
			(layer "B.SilkS")
		)
		(fp_poly
			(pts
				(xy 0.5334 0.254) (xy 0.635 0.254) (xy 0.635 0.2286) (xy 0.635 -0.254) (xy 0.5334 -0.254) (xy 0.5334 -0.2794)
				(xy -0.5334 -0.2794) (xy -0.5334 -0.254) (xy -0.635 -0.254) (xy -0.635 0.254) (xy -0.5334 0.254)
				(xy -0.5334 0.2794) (xy 0.508 0.2794) (xy 0.5334 0.2794)
			)
			(stroke
				(width 0)
				(type default)
			)
			(fill no)
			(layer "B.CrtYd")
		)
		(pad "1" smd rect
			(at -0.40005 0 90)
			(size 0.4572 0.508)
			(layers "B.Cu" "B.Mask" "B.Paste")
			(net "T7_NODE2_EN_R")
		)
		(pad "2" smd rect
			(at 0.40005 0 90)
			(size 0.4572 0.508)
			(layers "B.Cu" "B.Mask" "B.Paste")
			(net "GND")
		)
	)
	(footprint ""
		(layer "B.Cu")
		(at 53.961538 -83.468718 -90)
		(property "Reference" "C37"
			(at -0.917448 0.066548 270)
			(unlocked yes)
			(layer "B.SilkS")
			(effects
				(font
					(size 0.7874 0.5842)
					(thickness 0.1524)
				)
				(justify left mirror)
			)
		)
		(property "Value" ""
			(at 0 0 90)
			(layer "B.Fab")
			(effects
				(font
					(size 1.27 1.27)
				)
				(justify mirror)
			)
		)
		(duplicate_pad_numbers_are_jumpers no)
		(fp_line
			(start -0.7874 0.4064)
			(end 0.7874 0.4064)
			(stroke
				(width 0.1524)
				(type default)
			)
			(layer "B.SilkS")
		)
		(fp_line
			(start 0.7874 0.4064)
			(end 0.7874 -0.4064)
			(stroke
				(width 0.1524)
				(type default)
			)
			(layer "B.SilkS")
		)
		(fp_line
			(start 0 0.381)
			(end 0 -0.381)
			(stroke
				(width 0.1524)
				(type default)
			)
			(layer "B.SilkS")
		)
		(fp_line
			(start -0.7874 -0.4064)
			(end -0.7874 0.4064)
			(stroke
				(width 0.1524)
				(type default)
			)
			(layer "B.SilkS")
		)
		(fp_line
			(start 0.7874 -0.4064)
			(end -0.7874 -0.4064)
			(stroke
				(width 0.1524)
				(type default)
			)
			(layer "B.SilkS")
		)
		(fp_poly
			(pts
				(xy 0.5334 0.254) (xy 0.635 0.254) (xy 0.635 0.2286) (xy 0.635 -0.254) (xy 0.5334 -0.254) (xy 0.5334 -0.2794)
				(xy -0.5334 -0.2794) (xy -0.5334 -0.254) (xy -0.635 -0.254) (xy -0.635 0.254) (xy -0.5334 0.254)
				(xy -0.5334 0.2794) (xy 0.508 0.2794) (xy 0.5334 0.2794)
			)
			(stroke
				(width 0)
				(type default)
			)
			(fill no)
			(layer "B.CrtYd")
		)
		(pad "1" smd rect
			(at -0.40005 0 90)
			(size 0.4572 0.508)
			(layers "B.Cu" "B.Mask" "B.Paste")
			(net "P1V8_NODE1")
		)
		(pad "2" smd rect
			(at 0.40005 0 90)
			(size 0.4572 0.508)
			(layers "B.Cu" "B.Mask" "B.Paste")
			(net "GND")
		)
	)
	(footprint ""
		(layer "B.Cu")
		(at 105.14076 -185.205624 90)
		(property "Reference" "R899"
			(at 3.777996 -0.438658 270)
			(unlocked yes)
			(layer "B.SilkS")
			(effects
				(font
					(size 0.7874 0.5842)
					(thickness 0.1524)
				)
				(justify left mirror)
			)
		)
		(property "Value" ""
			(at 0 0 90)
			(layer "B.Fab")
			(effects
				(font
					(size 1.27 1.27)
				)
				(justify mirror)
			)
		)
		(duplicate_pad_numbers_are_jumpers no)
		(fp_line
			(start 0.7874 -0.4064)
			(end -0.7874 -0.4064)
			(stroke
				(width 0.1524)
				(type default)
			)
			(layer "B.SilkS")
		)
		(fp_line
			(start -0.7874 -0.4064)
			(end -0.7874 0.4064)
			(stroke
				(width 0.1524)
				(type default)
			)
			(layer "B.SilkS")
		)
		(fp_line
			(start 0.7874 0.4064)
			(end 0.7874 -0.4064)
			(stroke
				(width 0.1524)
				(type default)
			)
			(layer "B.SilkS")
		)
		(fp_line
			(start -0.7874 0.4064)
			(end 0.7874 0.4064)
			(stroke
				(width 0.1524)
				(type default)
			)
			(layer "B.SilkS")
		)
		(fp_poly
			(pts
				(xy 0.508 0.2794) (xy 0.508 0.2286) (xy 0.635 0.2286) (xy 0.635 -0.254) (xy 0.5334 -0.254) (xy 0.5334 -0.2794)
				(xy -0.5334 -0.2794) (xy -0.5334 -0.254) (xy -0.635 -0.254) (xy -0.635 0.254) (xy -0.5334 0.254)
				(xy -0.5334 0.2794)
			)
			(stroke
				(width 0)
				(type default)
			)
			(fill no)
			(layer "B.CrtYd")
		)
		(pad "1" smd rect
			(at -0.40005 0 270)
			(size 0.4572 0.508)
			(layers "B.Cu" "B.Mask" "B.Paste")
			(net "T5_NODE2_EN")
		)
		(pad "2" smd rect
			(at 0.40005 0 270)
			(size 0.4572 0.508)
			(layers "B.Cu" "B.Mask" "B.Paste")
			(net "T5_NODE2_EN_R")
		)
	)
)
